(kicad_pcb
	(version 20260206)
	(generator "pcbnew")
	(generator_version "10.0")
	(general
		(thickness 1.6)
		(legacy_teardrops no)
	)
	(paper "A4")
	(title_block
		(title "v1-pdb — T6M_PDB_D_0927_0900.brd")
		(comment 1 "Open CloudServer (Microsoft) / footprints 147-148 of 321")
	)
	(layers
		(0 "F.Cu" signal "TOP")
		(4 "In1.Cu" signal "GND")
		(6 "In2.Cu" signal "IN1")
		(8 "In3.Cu" signal "VCC")
		(10 "In4.Cu" signal "VCC1")
		(12 "In5.Cu" signal "IN2")
		(14 "In6.Cu" signal "GND1")
		(2 "B.Cu" signal "BOTTOM")
		(9 "F.Adhes" user "F.Adhesive")
		(11 "B.Adhes" user "B.Adhesive")
		(13 "F.Paste" user "Package Geometry/Pastemask Top")
		(15 "B.Paste" user "Package Geometry/Pastemask Bottom")
		(5 "F.SilkS" user "Ref Des/Silkscreen Top")
		(7 "B.SilkS" user "Ref Des/Silkscreen Bottom")
		(1 "F.Mask" user "Board Geometry/Soldermask Top")
		(3 "B.Mask" user "Board Geometry/Soldermask Bottom")
		(17 "Dwgs.User" user "User.Drawings")
		(19 "Cmts.User" user "User.Comments")
		(21 "Eco1.User" user "User.Eco1")
		(23 "Eco2.User" user "User.Eco2")
		(25 "Edge.Cuts" user "Board Geometry/Outline")
		(27 "Margin" user)
		(31 "F.CrtYd" user "Package Geometry/Place Bound Top")
		(29 "B.CrtYd" user "Package Geometry/Place Bound Bottom")
		(35 "F.Fab" user "Ref Des/Assembly Top")
		(33 "B.Fab" user "Ref Des/Assembly Bottom")
	)
	(footprint ""
		(layer "F.Cu")
		(at 26.947622 -108.230416)
		(property "Reference" "R7"
			(at -2.66192 0.007112 0)
			(unlocked yes)
			(layer "F.SilkS")
			(effects
				(font
					(size 0.7874 0.5842)
					(thickness 0.1524)
				)
				(justify left)
			)
		)
		(property "Value" ""
			(at 0 0 0)
			(layer "F.Fab")
			(effects
				(font
					(size 1.27 1.27)
				)
			)
		)
		(duplicate_pad_numbers_are_jumpers no)
		(fp_line
			(start -0.7874 -0.4064)
			(end 0.7874 -0.4064)
			(stroke
				(width 0.1524)
				(type default)
			)
			(layer "F.SilkS")
		)
		(fp_line
			(start -0.7874 0.4064)
			(end -0.7874 -0.4064)
			(stroke
				(width 0.1524)
				(type default)
			)
			(layer "F.SilkS")
		)
		(fp_line
			(start 0.7874 -0.4064)
			(end 0.7874 0.4064)
			(stroke
				(width 0.1524)
				(type default)
			)
			(layer "F.SilkS")
		)
		(fp_line
			(start 0.7874 0.4064)
			(end -0.7874 0.4064)
			(stroke
				(width 0.1524)
				(type default)
			)
			(layer "F.SilkS")
		)
		(fp_poly
			(pts
				(xy -0.508 0.2794) (xy -0.508 0.2286) (xy -0.635 0.2286) (xy -0.635 -0.254) (xy -0.5334 -0.254)
				(xy -0.5334 -0.2794) (xy 0.5334 -0.2794) (xy 0.5334 -0.254) (xy 0.635 -0.254) (xy 0.635 0.254) (xy 0.5334 0.254)
				(xy 0.5334 0.2794)
			)
			(stroke
				(width 0)
				(type default)
			)
			(fill no)
			(layer "F.CrtYd")
		)
		(pad "1" smd rect
			(at 0.40005 0)
			(size 0.4572 0.508)
			(layers "F.Cu" "F.Mask" "F.Paste")
			(net "PSU2_REMOTE_N")
		)
		(pad "2" smd rect
			(at -0.40005 0)
			(size 0.4572 0.508)
			(layers "F.Cu" "F.Mask" "F.Paste")
			(net "GND")
		)
	)
	(footprint ""
		(layer "F.Cu")
		(at 30.45968 -260.130036)
		(property "Reference" "J3"
			(at -4.153662 5.745988 0)
			(unlocked yes)
			(layer "F.SilkS")
			(effects
				(font
					(size 0.7874 0.5842)
					(thickness 0.1524)
				)
				(justify left)
			)
		)
		(property "Value" ""
			(at 0 0 0)
			(layer "F.Fab")
			(effects
				(font
					(size 1.27 1.27)
				)
			)
		)
		(duplicate_pad_numbers_are_jumpers no)
		(fp_line
			(start -2.135124 -4.560062)
			(end -2.135124 83.300062)
			(stroke
				(width 0.1524)
				(type default)
			)
			(layer "F.SilkS")
		)
		(fp_line
			(start -2.135124 83.300062)
			(end 7.215124 83.300062)
			(stroke
				(width 0.1524)
				(type default)
			)
			(layer "F.SilkS")
		)
		(fp_line
			(start 7.215124 -4.560062)
			(end -2.135124 -4.560062)
			(stroke
				(width 0.1524)
				(type default)
			)
			(layer "F.SilkS")
		)
		(fp_line
			(start 7.215124 83.300062)
			(end 7.215124 -4.560062)
			(stroke
				(width 0.1524)
				(type default)
			)
			(layer "F.SilkS")
		)
		(fp_poly
			(pts
				(xy -2.758694 -0.014732) (xy -5.458714 -0.714756) (xy -5.458714 0.685292)
			)
			(stroke
				(width 0)
				(type default)
			)
			(fill yes)
			(layer "F.SilkS")
		)
		(fp_poly
			(pts
				(xy -2.28219 -0.127) (xy -4.98221 -0.827024) (xy -4.98221 0.573024)
			)
			(stroke
				(width 0)
				(type default)
			)
			(fill yes)
			(layer "B.SilkS")
		)
		(fp_poly
			(pts
				(xy -0.8636 -0.8636) (xy -0.8636 79.6036) (xy -0.8636 79.629) (xy 5.9436 79.629) (xy 5.9436 79.6036)
				(xy 5.9436 -0.8636) (xy 5.9436 -0.889) (xy -0.8636 -0.889)
			)
			(stroke
				(width 0)
				(type default)
			)
			(fill no)
			(layer "B.CrtYd")
		)
		(fp_rect
			(start -2.135124 -4.560062)
			(end 7.21487 83.300062)
			(stroke
				(width 0)
				(type default)
			)
			(fill no)
			(layer "F.CrtYd")
		)
		(fp_line
			(start -2.135124 -4.560062)
			(end 7.215124 -4.560062)
			(stroke
				(width 0.1)
				(type default)
			)
			(layer "F.Fab")
		)
		(fp_line
			(start -2.135124 83.300062)
			(end -2.135124 -4.560062)
			(stroke
				(width 0.1)
				(type default)
			)
			(layer "F.Fab")
		)
		(fp_line
			(start 7.215124 -4.560062)
			(end 7.215124 83.300062)
			(stroke
				(width 0.1)
				(type default)
			)
			(layer "F.Fab")
		)
		(fp_line
			(start 7.215124 83.300062)
			(end -2.135124 83.300062)
			(stroke
				(width 0.1)
				(type default)
			)
			(layer "F.Fab")
		)
		(fp_text user "32"
			(at -3.66268 79.554324 0)
			(unlocked yes)
			(layer "F.SilkS")
			(effects
				(font
					(size 0.7874 0.5842)
					(thickness 0.1524)
				)
				(justify left)
			)
		)
		(fp_text user "1"
			(at -3.093974 -0.810768 0)
			(unlocked yes)
			(layer "F.SilkS")
			(effects
				(font
					(size 0.7874 0.5842)
					(thickness 0.1524)
				)
				(justify left)
			)
		)
		(fp_text user "64"
			(at 7.495794 -0.366014 0)
			(unlocked yes)
			(layer "F.SilkS")
			(effects
				(font
					(size 0.7874 0.5842)
					(thickness 0.1524)
				)
				(justify left)
			)
		)
		(fp_text user "33"
			(at 7.680706 82.813906 0)
			(unlocked yes)
			(layer "F.SilkS")
			(effects
				(font
					(size 0.7874 0.5842)
					(thickness 0.1524)
				)
				(justify left)
			)
		)
		(fp_text user "1"
			(at -1.689608 -0.958596 0)
			(unlocked yes)
			(layer "B.SilkS")
			(effects
				(font
					(size 0.7874 0.5842)
					(thickness 0.1524)
				)
				(justify left mirror)
			)
		)
		(fp_text user "32"
			(at -0.73152 79.809086 0)
			(unlocked yes)
			(layer "B.SilkS")
			(effects
				(font
					(size 0.7874 0.5842)
					(thickness 0.1524)
				)
				(justify left mirror)
			)
		)
		(fp_text user "64"
			(at 5.89153 -1.71323 0)
			(unlocked yes)
			(layer "B.SilkS")
			(effects
				(font
					(size 0.7874 0.5842)
					(thickness 0.1524)
				)
				(justify left mirror)
			)
		)
		(fp_text user "33"
			(at 6.095238 82.893154 0)
			(unlocked yes)
			(layer "B.SilkS")
			(effects
				(font
					(size 0.7874 0.5842)
					(thickness 0.1524)
				)
				(justify left mirror)
			)
		)
		(pad "1" thru_hole rect
			(at 0 0 270)
			(size 1.6256 1.6256)
			(drill 1.1176)
			(layers "*.Cu" "*.Mask")
			(remove_unused_layers no)
			(net "P12V")
			(clearance 0)
			(padstack
				(mode front_inner_back)
				(layer "Inner"
					(shape circle)
					(size 1.6256 1.6256)
					(clearance 0)
				)
				(layer "B.Cu"
					(shape rect)
					(size 1.6256 1.6256)
					(clearance 0)
				)
			)
		)
		(pad "2" thru_hole circle
			(at 0 2.54 270)
			(size 1.6256 1.6256)
			(drill 1.1176)
			(layers "*.Cu" "*.Mask")
			(remove_unused_layers no)
			(net "P12V")
			(clearance 0)
		)
		(pad "3" thru_hole circle
			(at 0 5.08 270)
			(size 1.6256 1.6256)
			(drill 1.1176)
			(layers "*.Cu" "*.Mask")
			(remove_unused_layers no)
			(net "P12V")
			(clearance 0)
		)
		(pad "4" thru_hole circle
			(at 0 7.62 270)
			(size 1.6256 1.6256)
			(drill 1.1176)
			(layers "*.Cu" "*.Mask")
			(remove_unused_layers no)
			(net "P12V")
			(clearance 0)
		)
		(pad "5" thru_hole circle
			(at 0 10.16 270)
			(size 1.6256 1.6256)
			(drill 1.1176)
			(layers "*.Cu" "*.Mask")
			(remove_unused_layers no)
			(net "P12V")
			(clearance 0)
		)
		(pad "6" thru_hole circle
			(at 0 12.7 270)
			(size 1.6256 1.6256)
			(drill 1.1176)
			(layers "*.Cu" "*.Mask")
			(remove_unused_layers no)
			(net "P12V")
			(clearance 0)
		)
		(pad "7" thru_hole circle
			(at 0 15.24 270)
			(size 1.6256 1.6256)
			(drill 1.1176)
			(layers "*.Cu" "*.Mask")
			(remove_unused_layers no)
			(net "P12V")
			(clearance 0)
		)
		(pad "8" thru_hole circle
			(at 0 17.78 270)
			(size 1.6256 1.6256)
			(drill 1.1176)
			(layers "*.Cu" "*.Mask")
			(remove_unused_layers no)
			(net "P12V")
			(clearance 0)
		)
		(pad "9" thru_hole circle
			(at 0 20.32 270)
			(size 1.6256 1.6256)
			(drill 1.1176)
			(layers "*.Cu" "*.Mask")
			(remove_unused_layers no)
			(net "P12V")
			(clearance 0)
		)
		(pad "10" thru_hole circle
			(at 0 22.86 270)
			(size 1.6256 1.6256)
			(drill 1.1176)
			(layers "*.Cu" "*.Mask")
			(remove_unused_layers no)
			(net "P12V")
			(clearance 0)
		)
		(pad "11" thru_hole circle
			(at 0 25.4 270)
			(size 1.6256 1.6256)
			(drill 1.1176)
			(layers "*.Cu" "*.Mask")
			(remove_unused_layers no)
			(net "P12V")
			(clearance 0)
		)
		(pad "12" thru_hole circle
			(at 0 27.94 270)
			(size 1.6256 1.6256)
			(drill 1.1176)
			(layers "*.Cu" "*.Mask")
			(remove_unused_layers no)
			(net "P12V")
			(clearance 0)
		)
		(pad "13" thru_hole circle
			(at 0 30.48 270)
			(size 1.6256 1.6256)
			(drill 1.1176)
			(layers "*.Cu" "*.Mask")
			(remove_unused_layers no)
			(net "GND")
			(clearance 0)
		)
		(pad "14" thru_hole circle
			(at 0 33.02 270)
			(size 1.6256 1.6256)
			(drill 1.1176)
			(layers "*.Cu" "*.Mask")
			(remove_unused_layers no)
			(net "GND")
			(clearance 0)
		)
		(pad "15" thru_hole circle
			(at 0 35.56 270)
			(size 1.6256 1.6256)
			(drill 1.1176)
			(layers "*.Cu" "*.Mask")
			(remove_unused_layers no)
			(net "GND")
			(clearance 0)
		)
		(pad "16" thru_hole circle
			(at 0 38.1 270)
			(size 1.6256 1.6256)
			(drill 1.1176)
			(layers "*.Cu" "*.Mask")
			(remove_unused_layers no)
			(net "GND")
			(clearance 0)
		)
		(pad "17" thru_hole circle
			(at 0 40.64 270)
			(size 1.6256 1.6256)
			(drill 1.1176)
			(layers "*.Cu" "*.Mask")
			(remove_unused_layers no)
			(net "GND")
			(clearance 0)
		)
		(pad "18" thru_hole circle
			(at 0 43.18 270)
			(size 1.6256 1.6256)
			(drill 1.1176)
			(layers "*.Cu" "*.Mask")
			(remove_unused_layers no)
			(net "GND")
			(clearance 0)
		)
		(pad "19" thru_hole circle
			(at 0 45.72 270)
			(size 1.6256 1.6256)
			(drill 1.1176)
			(layers "*.Cu" "*.Mask")
			(remove_unused_layers no)
			(net "GND")
			(clearance 0)
		)
		(pad "20" thru_hole circle
			(at 0 48.26 270)
			(size 1.6256 1.6256)
			(drill 1.1176)
			(layers "*.Cu" "*.Mask")
			(remove_unused_layers no)
			(net "GND")
			(clearance 0)
		)
		(pad "21" thru_hole circle
			(at 0 50.8 270)
			(size 1.6256 1.6256)
			(drill 1.1176)
			(layers "*.Cu" "*.Mask")
			(remove_unused_layers no)
			(net "GND")
			(clearance 0)
		)
		(pad "22" thru_hole circle
			(at 0 53.34 270)
			(size 1.6256 1.6256)
			(drill 1.1176)
			(layers "*.Cu" "*.Mask")
			(remove_unused_layers no)
			(net "GND")
			(clearance 0)
		)
		(pad "23" thru_hole circle
			(at 0 55.88 270)
			(size 1.6256 1.6256)
			(drill 1.1176)
			(layers "*.Cu" "*.Mask")
			(remove_unused_layers no)
			(net "GND")
			(clearance 0)
		)
		(pad "24" thru_hole circle
			(at 0 58.42 270)
			(size 1.6256 1.6256)
			(drill 1.1176)
			(layers "*.Cu" "*.Mask")
			(remove_unused_layers no)
			(net "GND")
			(clearance 0)
		)
		(pad "25" thru_hole circle
			(at 0 60.96 270)
			(size 1.6256 1.6256)
			(drill 1.1176)
			(layers "*.Cu" "*.Mask")
			(remove_unused_layers no)
			(net "Net_403")
			(clearance 0)
		)
		(pad "26" thru_hole circle
			(at 0 63.5 270)
			(size 1.6256 1.6256)
			(drill 1.1176)
			(layers "*.Cu" "*.Mask")
			(remove_unused_layers no)
			(net "PSU3_REMOTE_N")
			(clearance 0)
		)
		(pad "27" thru_hole circle
			(at 0 66.04 270)
			(size 1.6256 1.6256)
			(drill 1.1176)
			(layers "*.Cu" "*.Mask")
			(remove_unused_layers no)
			(net "PSU3_AC_OK")
			(clearance 0)
		)
		(pad "28" thru_hole circle
			(at 0 68.58 270)
			(size 1.6256 1.6256)
			(drill 1.1176)
			(layers "*.Cu" "*.Mask")
			(remove_unused_layers no)
			(net "PSU3_CSAHRE")
			(clearance 0)
		)
		(pad "29" thru_hole circle
			(at 0 71.12 270)
			(size 1.6256 1.6256)
			(drill 1.1176)
			(layers "*.Cu" "*.Mask")
			(remove_unused_layers no)
			(net "PSU3_PS_ON_N")
			(clearance 0)
		)
		(pad "30" thru_hole circle
			(at 0 73.66 270)
			(size 1.6256 1.6256)
			(drill 1.1176)
			(layers "*.Cu" "*.Mask")
			(remove_unused_layers no)
			(net "PSU3_PS_KILL")
			(clearance 0)
		)
		(pad "31" thru_hole circle
			(at 0 76.2 270)
			(size 1.6256 1.6256)
			(drill 1.1176)
			(layers "*.Cu" "*.Mask")
			(remove_unused_layers no)
			(net "PSU3_RESET")
			(clearance 0)
		)
		(pad "32" thru_hole circle
			(at 0 78.74 270)
			(size 1.6256 1.6256)
			(drill 1.1176)
			(layers "*.Cu" "*.Mask")
			(remove_unused_layers no)
			(net "PSU_ALERT_N")
			(clearance 0)
		)
		(pad "33" thru_hole circle
			(at 5.08 78.74 270)
			(size 1.6256 1.6256)
			(drill 1.1176)
			(layers "*.Cu" "*.Mask")
			(remove_unused_layers no)
			(net "I2C_PSU2_SDA")
			(clearance 0)
		)
		(pad "34" thru_hole circle
			(at 5.08 76.2 270)
			(size 1.6256 1.6256)
			(drill 1.1176)
			(layers "*.Cu" "*.Mask")
			(remove_unused_layers no)
			(net "Net_404")
			(clearance 0)
		)
		(pad "35" thru_hole circle
			(at 5.08 73.66 270)
			(size 1.6256 1.6256)
			(drill 1.1176)
			(layers "*.Cu" "*.Mask")
			(remove_unused_layers no)
			(net "I2C_PSU2_SCL")
			(clearance 0)
		)
		(pad "36" thru_hole circle
			(at 5.08 71.12 270)
			(size 1.6256 1.6256)
			(drill 1.1176)
			(layers "*.Cu" "*.Mask")
			(remove_unused_layers no)
			(net "PSU3_RETURN")
			(clearance 0)
		)
		(pad "37" thru_hole circle
			(at 5.08 68.58 270)
			(size 1.6256 1.6256)
			(drill 1.1176)
			(layers "*.Cu" "*.Mask")
			(remove_unused_layers no)
			(net "PSU3_DC_OK")
			(clearance 0)
		)
		(pad "38" thru_hole circle
			(at 5.08 66.04 270)
			(size 1.6256 1.6256)
			(drill 1.1176)
			(layers "*.Cu" "*.Mask")
			(remove_unused_layers no)
			(net "PSU3_AD0")
			(clearance 0)
		)
		(pad "39" thru_hole circle
			(at 5.08 63.5 270)
			(size 1.6256 1.6256)
			(drill 1.1176)
			(layers "*.Cu" "*.Mask")
			(remove_unused_layers no)
			(net "P12V_STBY")
			(clearance 0)
		)
		(pad "40" thru_hole circle
			(at 5.08 60.96 270)
			(size 1.6256 1.6256)
			(drill 1.1176)
			(layers "*.Cu" "*.Mask")
			(remove_unused_layers no)
			(net "PSU3_REMOTE_P")
			(clearance 0)
		)
		(pad "41" thru_hole circle
			(at 5.08 58.42 270)
			(size 1.6256 1.6256)
			(drill 1.1176)
			(layers "*.Cu" "*.Mask")
			(remove_unused_layers no)
			(net "GND")
			(clearance 0)
		)
		(pad "42" thru_hole circle
			(at 5.08 55.88 270)
			(size 1.6256 1.6256)
			(drill 1.1176)
			(layers "*.Cu" "*.Mask")
			(remove_unused_layers no)
			(net "GND")
			(clearance 0)
		)
		(pad "43" thru_hole circle
			(at 5.08 53.34 270)
			(size 1.6256 1.6256)
			(drill 1.1176)
			(layers "*.Cu" "*.Mask")
			(remove_unused_layers no)
			(net "GND")
			(clearance 0)
		)
		(pad "44" thru_hole circle
			(at 5.08 50.8 270)
			(size 1.6256 1.6256)
			(drill 1.1176)
			(layers "*.Cu" "*.Mask")
			(remove_unused_layers no)
			(net "GND")
			(clearance 0)
		)
		(pad "45" thru_hole circle
			(at 5.08 48.26 270)
			(size 1.6256 1.6256)
			(drill 1.1176)
			(layers "*.Cu" "*.Mask")
			(remove_unused_layers no)
			(net "GND")
			(clearance 0)
		)
		(pad "46" thru_hole circle
			(at 5.08 45.72 270)
			(size 1.6256 1.6256)
			(drill 1.1176)
			(layers "*.Cu" "*.Mask")
			(remove_unused_layers no)
			(net "GND")
			(clearance 0)
		)
		(pad "47" thru_hole circle
			(at 5.08 43.18 270)
			(size 1.6256 1.6256)
			(drill 1.1176)
			(layers "*.Cu" "*.Mask")
			(remove_unused_layers no)
			(net "GND")
			(clearance 0)
		)
		(pad "48" thru_hole circle
			(at 5.08 40.64 270)
			(size 1.6256 1.6256)
			(drill 1.1176)
			(layers "*.Cu" "*.Mask")
			(remove_unused_layers no)
			(net "GND")
			(clearance 0)
		)
		(pad "49" thru_hole circle
			(at 5.08 38.1 270)
			(size 1.6256 1.6256)
			(drill 1.1176)
			(layers "*.Cu" "*.Mask")
			(remove_unused_layers no)
			(net "GND")
			(clearance 0)
		)
		(pad "50" thru_hole circle
			(at 5.08 35.56 270)
			(size 1.6256 1.6256)
			(drill 1.1176)
			(layers "*.Cu" "*.Mask")
			(remove_unused_layers no)
			(net "GND")
			(clearance 0)
		)
		(pad "51" thru_hole circle
			(at 5.08 33.02 270)
			(size 1.6256 1.6256)
			(drill 1.1176)
			(layers "*.Cu" "*.Mask")
			(remove_unused_layers no)
			(net "GND")
			(clearance 0)
		)
		(pad "52" thru_hole circle
			(at 5.08 30.48 270)
			(size 1.6256 1.6256)
			(drill 1.1176)
			(layers "*.Cu" "*.Mask")
			(remove_unused_layers no)
			(net "GND")
			(clearance 0)
		)
		(pad "53" thru_hole circle
			(at 5.08 27.94 270)
			(size 1.6256 1.6256)
			(drill 1.1176)
			(layers "*.Cu" "*.Mask")
			(remove_unused_layers no)
			(net "P12V")
			(clearance 0)
		)
		(pad "54" thru_hole circle
			(at 5.08 25.4 270)
			(size 1.6256 1.6256)
			(drill 1.1176)
			(layers "*.Cu" "*.Mask")
			(remove_unused_layers no)
			(net "P12V")
			(clearance 0)
		)
		(pad "55" thru_hole circle
			(at 5.08 22.86 270)
			(size 1.6256 1.6256)
			(drill 1.1176)
			(layers "*.Cu" "*.Mask")
			(remove_unused_layers no)
			(net "P12V")
			(clearance 0)
		)
		(pad "56" thru_hole circle
			(at 5.08 20.32 270)
			(size 1.6256 1.6256)
			(drill 1.1176)
			(layers "*.Cu" "*.Mask")
			(remove_unused_layers no)
			(net "P12V")
			(clearance 0)
		)
		(pad "57" thru_hole circle
			(at 5.08 17.78 270)
			(size 1.6256 1.6256)
			(drill 1.1176)
			(layers "*.Cu" "*.Mask")
			(remove_unused_layers no)
			(net "P12V")
			(clearance 0)
		)
		(pad "58" thru_hole circle
			(at 5.08 15.24 270)
			(size 1.6256 1.6256)
			(drill 1.1176)
			(layers "*.Cu" "*.Mask")
			(remove_unused_layers no)
			(net "P12V")
			(clearance 0)
		)
		(pad "59" thru_hole circle
			(at 5.08 12.7 270)
			(size 1.6256 1.6256)
			(drill 1.1176)
			(layers "*.Cu" "*.Mask")
			(remove_unused_layers no)
			(net "P12V")
			(clearance 0)
		)
		(pad "60" thru_hole circle
			(at 5.08 10.16 270)
			(size 1.6256 1.6256)
			(drill 1.1176)
			(layers "*.Cu" "*.Mask")
			(remove_unused_layers no)
			(net "P12V")
			(clearance 0)
		)
		(pad "61" thru_hole circle
			(at 5.08 7.62 270)
			(size 1.6256 1.6256)
			(drill 1.1176)
			(layers "*.Cu" "*.Mask")
			(remove_unused_layers no)
			(net "P12V")
			(clearance 0)
		)
		(pad "62" thru_hole circle
			(at 5.08 5.08 270)
			(size 1.6256 1.6256)
			(drill 1.1176)
			(layers "*.Cu" "*.Mask")
			(remove_unused_layers no)
			(net "P12V")
			(clearance 0)
		)
		(pad "63" thru_hole circle
			(at 5.08 2.54 270)
			(size 1.6256 1.6256)
			(drill 1.1176)
			(layers "*.Cu" "*.Mask")
			(remove_unused_layers no)
			(net "P12V")
			(clearance 0)
		)
		(pad "64" thru_hole circle
			(at 5.08 0 270)
			(size 1.6256 1.6256)
			(drill 1.1176)
			(layers "*.Cu" "*.Mask")
			(remove_unused_layers no)
			(net "P12V")
			(clearance 0)
		)
	)
)
